# BASEBOARD_FAB2 (Tioga Pass) — schematic parts with pin connectivity, parts 4689–4708 of 4751; source: Cadence DE-HDL packaged netlist (pstxprt.dat, pstxnet.dat, pstchip.dat)

U8D7  LCMXO2_A  IC  pkg 256BGA  page 190
  A1  VCC(0)  POWER  = P3V3_STBY
  A2  NC(0)  NC  = NC
  A3  PT11C  BI  = FM_PCH_PRSNT_N
  A4  PT10A  BI  = FM_P3V3_CPLD_EN
  A5  PT11A  BI  = TP_CPLD1_PT11A
  A6  PT12D_TDI  BI  = JTAG_PLD_TDI
  A7  PT16C_TCK  BI  = JTAG_PLD_TCK
  A8  PT17B_PCLKC0_1  BI  = TP_CPLD1_PT17B_PCLKC0_1
  A9  PT18C_SCL_PCLKT0_0  BI  = SMB_SENSOR_STBY_LVC3_SCL
  A10  PT19B  BI  = FM_PVCCIN_PVCCSA_CPU0_EN_LVC1
  A11  PT21A  BI  = FM_CPU0_OR_CPU1_MCP_PRES
  A12  PT22B  BI  = PU_THERMTRIP_FORCE_N
  A13  PT24C_INITN  BI  = TP_CPLD1_PT24C_INITN
  A14  PT22D  BI  = TP_CPLD1_PT22D
  A15  PT24B  BI  = TP_CPLD1_PT24B
  A16  VCC(1)  POWER  = P3V3_STBY
  B1  PL1C  BI  = RST_PCIE_PCH_PERST_N
  B2  GND(0)  GROUND  = GND
  B3  PT9C  BI  = FM_CTNR_PS_ON
  B4  PT11D  BI  = PWRGD_PVTT_CPU0
  B5  PT9B  BI  = PWRGD_P12V_MAIN
  B6  PT11B  BI  = TP_CPLD1_PT11B
  B7  PT13A  BI  = TP_CPLD1_PT13A
  B8  PT16D_TMS  BI  = JTAG_PLD_TMS
  B9  PT19A  BI  = PU_RST_PERST_BIT1
  B10  PT20D_PROGRAMN  BI  = PU_CPLD1_PT20D_PROGRAMN
  B11  PT22A  BI  = PWRGD_DSW_PWROK
  B12  PT23B  BI  = FM_PCH_PWRBTN_R1_N
  B13  PT22C  BI  = TP_CPLD1_PT22C
  B14  PT24A  BI  = FM_SINT_PRSNT_N
  B15  GND(1)  GROUND  = GND
  B16  PR1D  BI  = FM_ADR_COMPLETE_DLY
  C1  PL2C  BI  = RST_PCIE_CPU_DEV1_N
  C2  PL1D  BI  = FM_PCH_PLD_DATA
  C3  GND(2)  GROUND  = GND
  C4  PT9A  BI  = FM_ADR_SMI_GPIO_R_N
  C5  PT10B  BI  = FM_CPU1_THERMTRIP_LATCH_LVT3_N
  C6  PT12C_TDO  BI  = JTAG_PLD_TDO
  C7  PT13B  BI  = FM_BMC_ONCTL_N
  C8  PT17A_PCLKT0_1  BI  = FM_ADR_COMPLETE
  C9  PT18D_SDA_PCLKC0_0  BI  = SMB_SENSOR_STBY_LVC3_SDA
  C10  PT20C_JTAGENB  BI  = FM_JTAG_PLD_EN_DEBUG
  C11  PT21B  BI  = FM_CPU0_CD_PRES
  C12  PT23A  BI  = FM_SLPS4_N
  C13  PT24D_DONE  BI  = TP_CPLD1_PT24D_DONE
  C14  GND(3)  GROUND  = GND
  C15  PR1C  BI  = FM_DB1200_PWRGD
  C16  PR2C  BI  = PWRGD_PCH_PWROK
  D1  PL1B_L_GPLLC_FB  BI  = TP_CPLD1_PL1B_L_GPLLC_FB
  D2  PL2D  BI  = FM_MEM_EVENT_FUNC
  D3  PL1A_L_GPLLT_FB  BI  = TP_CPLD1_PL1A_L_GPLLT_FB
  D4  GND(4)  GROUND  = GND
  D5  VCCIO0(3)  POWER  = P3V3_STBY
  D6  PT12A  BI  = RST_PCIE_CPU_DEV0_N
  D7  PT13D  BI  = FM_FORCE_ADR_N
  D8  PT17C  BI  = TP_CPLD1_PT17C
  D9  PT18B  BI  = RST_PCIE_MIDPLANE_N
  D10  PT20A  BI  = TP_CPLD1_PT20A
  D11  PT21D  BI  = FM_CPU0_AND_CPU1_MCP_PRES
  D12  VCCIO0(1)  POWER  = P3V3_STBY
  D13  GND(5)  GROUND  = GND
  D14  PR1A  BI  = PWRGD_SYS_PWROK
  D15  PR2D  BI  = PWRGD_P1V8MCP_CPU0
  D16  PR2A  BI  = PWRGD_P1V8MCP_CPU1
  E1  PL3A_PCLKT5_0  BI  = CLK_32K_SUSCLK_PLD
  E2  PL2A_L_GPLLT_IN  BI  = FM_CPU_CATERR_DLY_LVT3_N
  E3  PL2B_L_GPLLC_IN  BI  = TP_CPLD1_PL2B_L_GPLLC_IN
  E4  VCCIO5(0)  POWER  = P3V3_STBY
  E5  GND(6)  GROUND  = GND
  E6  PT13C  BI  = FM_CPU1_FIVR_FAULT_LVT3_N
  E7  PT12B  BI  = PWRGD_P1V15_BMC_STBY
  E8  PT16B  BI  = TP_CPLD1_PT16B
  E9  PT17D  BI  = FM_SLP_SUS_N
  E10  PT20B  BI  = TP_CPLD1_PT20B
  E11  PT19D  BI  = TP_CPLD1_PT19D
  E12  GND(7)  GROUND  = GND
  E13  VCCIO1(0)  POWER  = P3V3_STBY
  E14  PR2B  BI  = FM_CPLD_ADR_TRIGGER_N
  E15  PR1B  BI  = RST_PLTRST_N
  E16  PR3A  BI  = FM_P1V8MCP_CPU0_EN
  F1  PL4B  BI  = FM_CPU0_PROC_ID0
  F2  PL3B_PCLKC5_0  BI  = FM_CPU0_PKGID0
  F3  PL4A  BI  = FM_CPU0_PROC_ID1
  F4  PL3C  BI  = PU_RST_PERST_BIT0
  F5  PL5C  BI  = FM_CPU0_FIVR_FAULT_LVT3_N
  F6  GND(8)  GROUND  = GND
  F7  PT16A  BI  = FM_PLD_DEBUG_MODE_N
  F8  PT18A  BI  = SGPIO_BMC_DIN_R
  F9  PT19C  BI  = FM_PS_EN
  F10  PT21C  BI  = FM_CPU1_CD_PRES_N
  F11  GND(9)  GROUND  = GND
  F12  PR4C  BI  = FM_P1V8MCP_CPU1_EN
  F13  PR3C  BI  = PWRGD_CPUPWRGD
  F14  PR4A  BI  = RST_BMC_SYSRST_BTN_OUT_B_R1_N
  F15  PR3B  BI  = FM_CPU0_MCP_CLK_EN_N
  F16  PR4B  BI  = FM_CPU1_MCP_CLK_EN_N
  G1  PL6A  BI  = FM_SLPS3_N
  G2  PL5A  BI  = FM_CPU0_PKGID2
  G3  PL5B  BI  = FM_CPU0_PKGID1
  G4  PL4D  BI  = RST_RSMRST_R_N
  G5  PL4C  BI  = FM_DEBUG_RST_BTN_N
  G6  PL3D  BI  = FM_PWR_BTN_R2_N
  G7  VCC(4)  POWER  = P3V3_STBY
  G8  VCCIO0(0)  POWER  = P3V3_STBY
  G9  VCCIO0(2)  POWER  = P3V3_STBY
  G10  VCC(5)  POWER  = P3V3_STBY
  G11  PR5C  BI  = FM_WBG_PRSNT_N
  G12  PR3D  BI  = FM_CPU0_THERMTRIP_LATCH_LVT3_N
  G13  PR4D  BI  = FM_CPU1_FIVR_FAULT_LVT3
  G14  PR5B  BI  = FM_CPU1_THERMTRIP_LVT3_N
  G15  PR5A  BI  = FM_UV_ADR_TRIGGER_N
  G16  PR6A  BI  = FM_FAST_PROCHOT_THROTTLE_IN_N
  H1  PL7B  BI  = RST_PCIE_CPU_DEV3_N
  H2  PL6B  BI  = FM_PVCCMCP_CPU0_EN
  H3  PL7A  BI  = RST_PCIE_CPU_DEV2_N
  H4  PL6C  BI  = FM_MP_PS_FAIL_N
  H5  PL9C  BI  = NC
  H6  PL5D  BI  = PWRGD_P3V3
  H7  VCCIO4(1)  POWER  = P3V3_STBY
  H8  GND(10)  GROUND  = GND
  H9  GND(11)  GROUND  = GND
  H10  VCCIO1(1)  POWER  = P3V3_STBY
  H11  PR9C  BI  = TP_CPLD1_PR9C
  H12  PR5D  BI  = FM_UV_ADR_TRIGGER_EN
  H13  PR6C  BI  = FM_PVDDQ_GHJ_EN
  H14  PR7A_PCLKT1_0  BI  = TP_CPLD1_PR7A_PCLKT1_0
  H15  PR6B  BI  = FM_PVDDQ_KLM_EN
  H16  PR7B_PCLKC1_0  BI  = TP_CPLD1_PR7B_PCLKC1_0
  J1  PL7C_PCLKT4_0  BI  = SGPIO_BMC_CLK
  J2  PL9A  BI  = SGPIO_BMC_DOUT
  J3  PL7D_PCLKC4_0  BI  = TP_CPLD1_PL7D_PCLKT4_0
  J4  PL9D  BI  = NC
  J5  PL10C  BI  = UART_BMC_RXD5
  J6  PL6D  BI  = PWRGD_P5V
  J7  VCCIO4(0)  POWER  = P3V3_STBY
  J8  GND(12)  GROUND  = GND
  J9  GND(13)  GROUND  = GND
  J10  VCCIO1(2)  POWER  = P3V3_STBY
  J11  PR10C  BI  = TP_CPLD1_PR10C
  J12  PR6D  BI  = FM_FAST_PROCHOT_THROTTLE_DLY_N
  J13  PR9D  BI  = TP_CPLD1_PR9D
  J14  PR7D  BI  = TP_CPLD1_PR7D
  J15  PR9A  BI  = TP_CPLD1_PR9A
  J16  PR7C  BI  = TP_CPLD1_PR7C
  K1  PL9B  BI  = FM_PVCCIOMCP_CPU0_EN
  K2  PL10B  BI  = SP1_BMC_HOST_UART_TX
  K3  PL10A  BI  = SP1_BMC_HOST_UART_RX
  K4  PL11C  BI  = SGPIO_BMC_LD_N
  K5  PL12C  BI  = PWRGD_PVCCIN_CPU0
  K6  PL10D  BI  = UART_BMC_TXD5
  K7  VCC(6)  POWER  = P3V3_STBY
  K8  VCCIO2(2)  POWER  = P3V3_STBY
  K9  VCCIO2(0)  POWER  = P3V3_STBY
  K10  VCC(7)  POWER  = P3V3_STBY
  K11  PR12C  BI  = RST_PLTRST_BUF_N
  K12  PR11D  BI  = FM_MEM_THERM_EVENT_PCH_N
  K13  PR11C  BI  = FM_MEM_THERM_EVENT_LVT3_N
  K14  PR10A  BI  = FM_PVDDQ_ABC_EN
  K15  PR10B  BI  = FM_PVDDQ_DEF_EN
  K16  PR9B  BI  = PU_FAB2_MARKER_CPLD
  L1  PL11A  BI  = PWRGD_PVSA_CPU0
  L2  PL12A_PCLKT3_0  BI  = CLK_25M_CPLD
  L3  PL11B  BI  = TP_CPLD1_PL11A
  L4  PL12D  BI  = PWRGD_PVCCMCP_CPU1
  L5  PL11D  BI  = PWRGD_CPU0_LVC3
  L6  GND(14)  GROUND  = GND
  L7  PB8D  BI  = FM_OC0_USB_N
  L8  PB11D  BI  = PWRGD_PVCCIO_CPU0
  L9  PB12D  BI  = FM_IE_DISABLE_N
  L10  PB18D  BI  = FM_SOL_UART_CH_SEL
  L11  GND(15)  GROUND  = GND
  L12  PR10D  BI  = PWRGD_P3V3_STBY
  L13  PR12D  BI  = TP_CPLD1_PR12D
  L14  PR11B  BI  = TP_CPLD1_PR11B
  L15  PR12A  BI  = FM_THERMTRIP_DLY
  L16  PR11A  BI  = PWRGD_PVCCIO_CPU1
  M1  PL12B_PCLKC3_0  BI  = RST_RSMRST_DLY
  M2  PL14A  BI  = PWRGD_PVPP_GHJ
  M3  PL13A  BI  = RST_PCIE_RISER1_PERST_N
  M4  VCCIO3(0)  POWER  = P3V3_STBY
  M5  GND(16)  GROUND  = GND
  M6  PB11C  BI  = PWRGD_PVPP_DEF
  M7  PB9C  BI  = FM_PVCCIO_CPU0_EN
  M8  PB16C  BI  = FM_PVCCMCP_CPU1_EN
  M9  PB18C  BI  = FM_CPLD_UART_CH_LOCK_N
  M10  PB21C  BI  = PWRGD_CPU1_LVC3
  M11  PB19D  BI  = XDP_PWRGD_RST_N
  M12  GND(17)  GROUND  = GND
  M13  VCCIO1(3)  POWER  = P3V3_STBY
  M14  PR13A  BI  = FM_CPU1_PROC_ID1
  M15  PR13B  BI  = FM_CPU1_PROC_ID0
  M16  PR12B  BI  = FM_CPU0_FIVR_FAULT_LVT3
  N1  PL13B  BI  = PWRGD_PVCCIN_CPU1
  N2  PL13C  BI  = PWRGD_PVPP_KLM
  N3  PL14B  BI  = RST_CD_CPU0_POR_N
  N4  GND(18)  GROUND  = GND
  N5  VCCIO2(3)  POWER  = P3V3_STBY
  N6  PB8C  BI  = PWRGD_PVCCIOMCP_CPU0
  N7  PB9D  BI  = PWRGD_PVPP_ABC
  N8  PB12C  BI  = FM_156M_CPU1_BRD_OSC_EN
  N9  PB16D  BI  = FM_CPLD_BMC_PWRDN_N
  N10  PB19C  BI  = RST_CPU1_LVC3_R1_N
  N11  PB21D  BI  = XDP_SYSPWROK
  N12  VCCIO2(1)  POWER  = P3V3_STBY
  N13  GND(19)  GROUND  = GND
  N14  PR14B  BI  = FM_CPU1_VRM_OSC_EN
  N15  PR13C  BI  = FM_CPU0_THERMTRIP_LVT3_N
  N16  PR14A  BI  = FM_PVCCIN_PVCCSA_CPU1_EN_LVC1
  P1  PL13D  BI  = FM_GLOBAL_RST_WARN_N
  P2  PL14D  BI  = FM_UART_ALERT_N
  P3  GND(20)  GROUND  = GND
  P4  PB3A  BI  = FM_CPU1_RC_EN
  P5  PB5B  BI  = PWRGD_PVCCMCP_CPU0
  P6  PB8A_MCLK_CCLK  BI  = TP_CPLD1_PB8A_MCLK_CCLK
  P7  PB9B  BI  = FM_PVCCIOMCP_CPU1_EN
  P8  PB12A  BI  = PWRGD_PVNN_P1V05_PCH
  P9  PB16B_PCLKC2_1  BI  = TP_CPLD1_PB16B_PCLKC2_1
  P10  PB19A  BI  = RST_CD_CPU1_POR_N
  P11  PB21B  BI  = FM_UARTSW_MSB_N
  P12  PB24A  BI  = FM_CPU1_PKGID1
  P13  PB25B_SI_SISPI  BI  = TP_CPLD1_PB25B_SI_SISPI
  P14  GND(21)  GROUND  = GND
  P15  PR14C  BI  = FM_PVPP_CPU0_EN
  P16  PR13D  BI  = FM_PVPP_CPU1_EN
  R1  PL14C  BI  = FM_BMC_CPLD_GPO
  R2  GND(22)  GROUND  = GND
  R3  PB3D  BI  = FM_CPU0_RC_EN
  R4  PB6D  BI  = FM_BMC_CPLD_MP_RST_N
  R5  PB5A_CSSPIN  BI  = TP_CPLD1_PB5A_CSSPIN
  R6  PB6B  BI  = RST_PCIE_M2_DEV_N
  R7  PB9A  BI  = PWRGD_PVTT_CPU1
  R8  PB11B_PCLKC2_0  BI  = FM_CPLD_USB_P0_EN_N
  R9  PB18A  BI  = FM_UARTSW_LSB_N
  R10  PB19B  BI  = RST_CPU0_LVC3_R1_N
  R11  PB22A  BI  = FM_DB1200ZL_BCLKS_EN_N
  R12  PB25A_SN  BI  = FM_CPU1_PKGID0
  R13  PB22C  BI  = FM_CPU0_VRM_OSC_EN
  R14  PB25D  BI  = FM_CPU_CATERR_LVT3_N
  R15  GND(23)  GROUND  = GND
  R16  PR14D  BI  = FM_P12V_MAIN_SW_EN
  T1  VCC(2)  POWER  = P3V3_STBY
  T2  PB3C  BI  = FM_ADR_MODE_SEL
  T3  PB6C  BI  = FM_DIS_ADR_DLY
  T4  PB3B  BI  = PWRGD_PVSA_CPU1
  T5  PB6A  BI  = PWRGD_PVCCIOMCP_CPU1
  T6  PB8B_SO_SPISO  BI  = TP_CPLD1_PB8B_SO_SPISO
  T7  PB11A_PCLKT2_0  BI  = FM_PVCCIO_CPU1_EN
  T8  PB12B  BI  = FM_CPLD_DBG_PWR_EN_N
  T9  PB16A_PCLKT2_1  BI  = TP_CPLD1_PB16A_PCLKT2_1
  T10  PB18B  BI  = FM_156M_CPU0_BRD_OSC_EN
  T11  PB21A  BI  = FM_CPU1_PKGID2
  T12  PB22B  BI  = FM_CPU1_SKTOCC_LVT3_N
  T13  PB24B  BI  = FM_CPU_MSMI_LVT3_N
  T14  PB22D  BI  = FM_CPU0_SKTOCC_LVT3_N
  T15  PB25C  BI  = PWRGD_DRAMPWRGD
  T16  VCC(3)  POWER  = P3V3_STBY

U8D8  TPS3700  IC  pkg SM  page 196
  1  OUTB  OUT  = PWRGD_P5V_N
  2  VDD  POWER  = P3V3_STBY
  3  INBN  BI  = A_PG_P5V
  4  INAP  BI  = A_PG_P12V_MAIN
  5  GND  GROUND  = GND
  6  OUTA  OUT  = PWRGD_P12V_MAIN_R

U8E1  TTL08  74LVC08A IC  pkg QFN15  page 170
  1  A(0)  IN  = IRQ_FORCE_NM_THROTTLE_N
  2  B(0)  IN  = FM_OC_DETECT_N
  3  Y(0)  OUT  = FM_FAST_PROCHOT_AND_OUT_0_N
  4  A(0)  IN  = IRQ_UV_DETECT_N
  5  B(0)  IN  = FM_HSC_TIMER_EXP_N
  6  Y(0)  OUT  = FM_FAST_PROCHOT_AND_OUT_1_N
  8  Y(0)  OUT  = FM_CTNR_PS_ON_R
  9  A(0)  IN  = FM_PS_EN
  10  B(0)  IN  = PWRGD_P12V_HSC_DLY
  11  Y(0)  OUT  = FM_FAST_PROCHOT_THROTTLE_IN_N
  12  A(0)  IN  = FM_FAST_PROCHOT_AND_OUT_0_N
  13  B(0)  IN  = FM_FAST_PROCHOT_AND_OUT_1_N

U8E2  ADM809  IC  pkg SMLF  page 196 : 2 = PWRGD_P12V_HSC_DLY_R ; 3 = PWRGD_P12V_HSC

U8E3  TTL1G126_A  74HC1G126 IC  pkg SOT  page 136
  1  OE  IN  = RST_PLTRST_TOP_SWAP
  2  A  IN  = FM_BIOS_TOP_SWAP
  4  Y  OUT  = FM_BIOS_TOP_SWAP_SPKR_R

U8E4  TTL1G126_A  74HC1G126 IC  pkg SOT  page 142
  1  OE  IN  = PU_TRI_STATE_EN
  2  A  IN  = FM_ALL_WAKE_N
  4  Y  OUT  = IRQ_LVC3_WAKE_R_N

U8F1  PI3B3257A  IC  pkg TSSOPLF  page 154
  1  S  BI  = FM_BIOS_SPI_BMC_CTRL
  2  IA0  BI  = SPI_PCH_CLK
  3  IA1  BI  = SPI_BMC_CLK
  4  YA  BI  = SPI_SWITCH_CLK
  5  IB0  BI  = SPI_PCH_MOSI
  6  IB1  BI  = SPI_BMC_DO
  7  YB  BI  = SPI_SWITCH_MOSI
  8  GND  POWER  = GND
  9  YC  BI  = SPI_SWITCH_CS0_N
  10  IC1  BI  = SPI_BMC_CS0_N
  11  IC0  BI  = SPI_PCH_CS0_N
  12  YD  BI  = SPI_SWITCH_MISO
  13  ID1  BI  = SPI_BMC_DI
  14  ID0  BI  = SPI_PCH_MISO_R
  15  EN  IN  = GND
  16  VCC  POWER  = P3V3_STBY

U8F2  W25Q128  IC  pkg SKT16  page 162
  1  HOLD_N_IO(3)  BI  = PU_SPI_BMC_BT_HOLD_N
  2  VCC  POWER  = P3V3_STBY
  3  RESET_N  IN  = PU_SPI_FLASH_RESET_2_N
  4  NC(0)  NC  = TP_SPI_2_0
  5  NC(1)  NC  = TP_SPI_2_1
  6  NC(2)  NC  = TP_SPI_2_2
  7  CS_N  IN  = SPI_BMC_BT_CS_N
  8  DO_IO(1)  BI  = SPI_BMC_BT_DI_R
  9  WP_N_IO(2)  BI  = PU_SPI_BMC_BT_WP_N
  10  GND  GROUND  = GND
  11  NC(3)  NC  = TP_SPI_2_3
  12  NC(4)  NC  = TP_SPI_2_4
  13  NC(5)  NC  = TP_SPI_2_5
  14  NC(6)  NC  = TP_SPI_2_6
  15  DI_IO(0)  BI  = SPI_BMC_BT_DO
  16  CLK  IN  = SPI_BMC_BT_CLK

U8F3  SN74LVC2G07DCKR-GP  pkg DISCRET-G4  page 156
  1  \1a\  IN  = RST_BMC_SYSRST_BTN_OUT_N
  2  GND  POWER  = GND
  3  \2a\  IN  = FM_BMC_PWRBTN_OUT_N
  4  \2y\  OUT  = FM_PCH_PWRBTN_R_N
  5  VCC  POWER  = P3V3_STBY
  6  \1y\  OUT  = RST_BMC_SYSRST_BTN_OUT_B_R_N

U8G1  SN74LVC2G07DCKR-GP  pkg DISCRET-G4  page 156
  1  \1a\  IN  = RST_PCH_SYSRST_BTN_OUT_N
  2  GND  POWER  = GND
  3  \2a\  IN  = FM_PCH_PWRBTN_OUT_N
  4  \2y\  OUT  = FM_PCH_PWRBTN_R_N
  5  VCC  POWER  = P3V3_STBY
  6  \1y\  OUT  = RST_BMC_SYSRST_BTN_OUT_B_R_N

U8G2  TTL1G07_A  74LVC1G07 IC  pkg SOP  page 161 : 2 = FAN_PWM_OUT_SYS0 ; 4 = FAN_PWM_OUT_SYS0_BUF
U8G3  TTL1G07_A  74LVC1G07 IC  pkg SOP  page 161 : 2 = FAN_PWM_OUT_SYS1 ; 4 = FAN_PWM_OUT_SYS1_BUF

U8W1  74CBTLV1G125  IC  pkg SMLF  page 245
  1  OE_N  IN  = JTAG_RISER_N
  2  A  IN  = JTAG_PLD_TDO
  4  B  OUT  = JTAG_RISER_TDI_R

U8W2  NC7SB3157  IC  pkg SMLF  page 245
  1  B1  UNSPEC  = JTAG_PLD_TDO
  2  GND  UNSPEC  = GND
  3  B0  UNSPEC  = JTAG_RISER_TDO_R
  4  A  UNSPEC  = JTAG_PLD_TDO_MUX_R
  5  VCC  UNSPEC  = P3V3_STBY
  6  S  UNSPEC  = JTAG_RISER_N

U9A1  TTL1G07_A  74LVC1G07 IC  pkg SOP  page 155 : 2 = SPA_5V_SIN_SW_D ; 4 = SPA_SIN_SW_R

U9A3  TC7PZ14FU-GP  pkg DISCRET-GA1  page 175
  1  \1a\  IN  = FP_RST_BTN_R_N
  2  GND  POWER  = GND
  3  \2a\  IN  = FP_RST_BTN_BUF1_N
  4  \2y\  OUT  = RST_SYSTEM_BTN_BUF_N
  5  VCC  POWER  = P3V3_STBY
  6  \1y\  OUT  = FP_RST_BTN_BUF1_N

U9A4  TC7PZ14FU-GP  pkg DISCRET-GA1  page 175
  1  \1a\  IN  = FP_PWR_BTN_R1_N
  2  GND  POWER  = GND
  3  \2a\  IN  = FP_PWR_BTN_BUF1_N
  4  \2y\  OUT  = FM_PWR_BTN_R_N
  5  VCC  POWER  = P3V3_STBY
  6  \1y\  OUT  = FP_PWR_BTN_BUF1_N

U9A5  74CBTLV1G125  IC  pkg SMLF  page 113
  1  OE_N  IN  = FM_CPU0_OR_CPU1_MCP_PRES
  2  A  IN  = JTAG_MCP_TCK_R1
  4  B  OUT  = GND

U9B4  TMP421  IC  pkg TSSOP  page 167
  1  DXP  IN  = ISENSE_TMP421_1_DXP
  2  DXN  IN  = ISENSE_TMP421_1_DXN
  3  A(1)  IN  = PU_TMP421_1_A1
  4  A(0)  IN  = PD_TMP421_1_A0
  5  GND  GROUND  = GND
  6  SDA  BI  = SMB_SENSOR_TMP421_1_SDA
  7  SCL  BI  = SMB_SENSOR_TMP421_1_SCL
  8  VP  POWER  = P3V3_STBY

U9E1  M25PE16  IC  pkg SM  page 140
  1  S_N  IN  = SPI_NIC_CS_N
  2  DQ1  OUT  = SPI_NIC_MISO_R
  3  W_N  IN  = PU_NV_WP_N
  4  VSS  GROUND  = GND
  5  DQ0  IN  = SPI_NIC_MOSI
  6  C  IN  = SPI_NIC_SCLK
  7  RESET_N  IN  = PU_NV_HOLD_N
  8  VCC  POWER  = P3V3_STBY
